# SCM (Grand Teton) — schematic netlist excerpt (pin names and nets, part order shuffled) for the footprints in the layout excerpt that follows; sources: Cadence DE-HDL packaged netlist, KiCad conversion of 12092022_DA0F0TMDCD0_F0T_Management_Board_D_brd_V3_OCP.brd

PC250  Q_CAP  1UF 25V 10% X6S  pkg C0402  page 55 : A = P1V2_AUX_VCC ; B = GND

(kicad_pcb
	(version 20260206)
	(generator "pcbnew")
	(generator_version "10.0")
	(general
		(thickness 1.6)
		(legacy_teardrops no)
	)
	(paper "A4")
	(title_block
		(title "12092022_DA0F0TMDCD0_F0T_Management_Board_D_brd_V3_OCP.brd")
		(comment 1 "Grand Teton / footprints 156-156 of 1440")
	)
	(layers
		(0 "F.Cu" signal "TOP")
		(4 "In1.Cu" signal "GND")
		(6 "In2.Cu" signal "IN1")
		(8 "In3.Cu" signal "GND1")
		(10 "In4.Cu" signal "IN2")
		(12 "In5.Cu" signal "VCC")
		(14 "In6.Cu" signal "VCC1")
		(16 "In7.Cu" signal "IN3")
		(18 "In8.Cu" signal "GND2")
		(20 "In9.Cu" signal "IN4")
		(22 "In10.Cu" signal "GND3")
		(2 "B.Cu" signal "BOTTOM")
		(9 "F.Adhes" user "F.Adhesive")
		(11 "B.Adhes" user "B.Adhesive")
		(13 "F.Paste" user "Package Geometry/Pastemask Top")
		(15 "B.Paste" user "Package Geometry/Pastemask Bottom")
		(5 "F.SilkS" user "Ref Des/Silkscreen Top")
		(7 "B.SilkS" user "Ref Des/Silkscreen Bottom")
		(1 "F.Mask" user "Board Geometry/Soldermask Top")
		(3 "B.Mask" user "Board Geometry/Soldermask Bottom")
		(17 "Dwgs.User" user "User.Drawings")
		(19 "Cmts.User" user "User.Comments")
		(21 "Eco1.User" user "User.Eco1")
		(23 "Eco2.User" user "User.Eco2")
		(25 "Edge.Cuts" user "Board Geometry/Outline")
		(27 "Margin" user)
		(31 "F.CrtYd" user "Package Geometry/Place Bound Top")
		(29 "B.CrtYd" user "Package Geometry/Place Bound Bottom")
		(35 "F.Fab" user "Ref Des/Assembly Top")
		(33 "B.Fab" user "Ref Des/Assembly Bottom")
	)
	(footprint ""
		(layer "F.Cu")
		(at 84.792312 -72.333358 90)
		(property "Reference" "PC250"
			(at 0 0 90)
			(layer "F.SilkS")
			(hide yes)
			(effects
				(font
					(size 1.27 1.27)
				)
			)
		)
		(property "Value" ""
			(at 0 0 90)
			(layer "F.Fab")
			(effects
				(font
					(size 1.27 1.27)
				)
			)
		)
		(duplicate_pad_numbers_are_jumpers no)
		(fp_line
			(start 0.7874 -0.4064)
			(end 0.7874 0.4064)
			(stroke
				(width 0.1524)
				(type default)
			)
			(layer "F.SilkS")
		)
		(fp_line
			(start -0.7874 -0.4064)
			(end 0.7874 -0.4064)
			(stroke
				(width 0.1524)
				(type default)
			)
			(layer "F.SilkS")
		)
		(fp_line
			(start 0.7874 0.4064)
			(end -0.7874 0.4064)
			(stroke
				(width 0.1524)
				(type default)
			)
			(layer "F.SilkS")
		)
		(fp_line
			(start -0.7874 0.4064)
			(end -0.7874 -0.4064)
			(stroke
				(width 0.1524)
				(type default)
			)
			(layer "F.SilkS")
		)
		(fp_line
			(start -0.12065 -0.305054)
			(end -0.12065 -0.2794)
			(stroke
				(width 0.1)
				(type default)
			)
			(layer "F.Fab")
		)
		(fp_line
			(start -0.67945 -0.305054)
			(end -0.12065 -0.305054)
			(stroke
				(width 0.1)
				(type default)
			)
			(layer "F.Fab")
		)
		(fp_line
			(start 0.67945 -0.3048)
			(end 0.67945 0.3048)
			(stroke
				(width 0.1)
				(type default)
			)
			(layer "F.Fab")
		)
		(fp_line
			(start 0.12065 -0.3048)
			(end 0.67945 -0.3048)
			(stroke
				(width 0.1)
				(type default)
			)
			(layer "F.Fab")
		)
		(fp_line
			(start 0.12065 -0.2794)
			(end 0.12065 -0.3048)
			(stroke
				(width 0.1)
				(type default)
			)
			(layer "F.Fab")
		)
		(fp_line
			(start -0.12065 -0.2794)
			(end 0.12065 -0.2794)
			(stroke
				(width 0.1)
				(type default)
			)
			(layer "F.Fab")
		)
		(fp_line
			(start 0.120396 0.2794)
			(end -0.12065 0.2794)
			(stroke
				(width 0.1)
				(type default)
			)
			(layer "F.Fab")
		)
		(fp_line
			(start -0.12065 0.2794)
			(end -0.12065 0.3048)
			(stroke
				(width 0.1)
				(type default)
			)
			(layer "F.Fab")
		)
		(fp_line
			(start 0.67945 0.3048)
			(end 0.120396 0.3048)
			(stroke
				(width 0.1)
				(type default)
			)
			(layer "F.Fab")
		)
		(fp_line
			(start 0.120396 0.3048)
			(end 0.120396 0.2794)
			(stroke
				(width 0.1)
				(type default)
			)
			(layer "F.Fab")
		)
		(fp_line
			(start -0.12065 0.3048)
			(end -0.67945 0.3048)
			(stroke
				(width 0.1)
				(type default)
			)
			(layer "F.Fab")
		)
		(fp_line
			(start -0.67945 0.3048)
			(end -0.67945 -0.305054)
			(stroke
				(width 0.1)
				(type default)
			)
			(layer "F.Fab")
		)
		(pad "1" smd circle
			(at -0.40005 0 90)
			(size 0 0)
			(layers "F.Cu" "F.Mask" "F.Paste")
			(net "P1V2_AUX_VCC")
		)
		(pad "2" smd circle
			(at 0.40005 0 90)
			(size 0 0)
			(layers "F.Cu" "F.Mask" "F.Paste")
			(net "GND")
		)
	)
)
